(kicad_pcb
	(version 20260206)
	(generator "pcbnew")
	(generator_version "10.0")
	(general
		(thickness 1.6)
		(legacy_teardrops no)
	)
	(paper "A4")
	(title_block
		(title "03242023_DA0F0TMBIJ0_F0T_Motherboard_J_brd_V01_OCP.brd")
		(comment 1 "Grand Teton / footprint 3483 of 6105 (J59), pads 1-71 of 71")
	)
	(layers
		(0 "F.Cu" signal "TOP")
		(4 "In1.Cu" signal "GND")
		(6 "In2.Cu" signal "IN1")
		(8 "In3.Cu" signal "GND1")
		(10 "In4.Cu" signal "IN2")
		(12 "In5.Cu" signal "GND2")
		(14 "In6.Cu" signal "IN3")
		(16 "In7.Cu" signal "GND3")
		(18 "In8.Cu" signal "VCC")
		(20 "In9.Cu" signal "VCC1")
		(22 "In10.Cu" signal "GND4")
		(24 "In11.Cu" signal "IN4")
		(26 "In12.Cu" signal "GND5")
		(28 "In13.Cu" signal "IN5")
		(30 "In14.Cu" signal "GND6")
		(32 "In15.Cu" signal "IN6")
		(34 "In16.Cu" signal "GND7")
		(2 "B.Cu" signal "BOTTOM")
		(9 "F.Adhes" user "F.Adhesive")
		(11 "B.Adhes" user "B.Adhesive")
		(13 "F.Paste" user "Package Geometry/Pastemask Top")
		(15 "B.Paste" user "Package Geometry/Pastemask Bottom")
		(5 "F.SilkS" user "Ref Des/Silkscreen Top")
		(7 "B.SilkS" user "Ref Des/Silkscreen Bottom")
		(1 "F.Mask" user "Board Geometry/Soldermask Top")
		(3 "B.Mask" user "Board Geometry/Soldermask Bottom")
		(17 "Dwgs.User" user "User.Drawings")
		(19 "Cmts.User" user "User.Comments")
		(21 "Eco1.User" user "User.Eco1")
		(23 "Eco2.User" user "User.Eco2")
		(25 "Edge.Cuts" user "Board Geometry/Outline")
		(27 "Margin" user)
		(31 "F.CrtYd" user "Package Geometry/Place Bound Top")
		(29 "B.CrtYd" user "Package Geometry/Place Bound Bottom")
		(35 "F.Fab" user "Ref Des/Assembly Top")
		(33 "B.Fab" user "Ref Des/Assembly Bottom")
	)
	(footprint ""
		(layer "F.Cu")
		(at 173.358048 -47.049944)
		(property "Reference" "J59"
			(at 5.590032 -12.227814 0)
			(unlocked yes)
			(layer "F.SilkS")
			(effects
				(font
					(size 0.7874 0.5842)
					(thickness 0.1524)
				)
				(justify left)
			)
		)
		(property "Value" ""
			(at 0 0 0)
			(layer "F.Fab")
			(effects
				(font
					(size 1.27 1.27)
				)
			)
		)
		(duplicate_pad_numbers_are_jumpers no)
		(pad "" np_thru_hole circle
			(at -1.525016 -9.99998 270)
			(size 1.1684 1.1684)
			(drill 1.1684)
			(layers "*.Cu" "*.Mask")
			(clearance 0.381)
			(thermal_gap 0.381)
		)
		(pad "" np_thru_hole circle
			(at -1.525016 9.99998 270)
			(size 1.651 1.651)
			(drill 1.651)
			(layers "*.Cu" "*.Mask")
			(clearance 0.381)
			(thermal_gap 0.381)
		)
		(pad "1" smd rect
			(at 3.750056 -9.249918 270)
			(size 0.2794 1.6002)
			(layers "F.Cu" "F.Mask" "F.Paste")
			(net "PCIE_M2_SSD0_PRSNT_N")
		)
		(pad "2" smd rect
			(at -3.800094 -8.999982 270)
			(size 0.2794 1.6002)
			(layers "F.Cu" "F.Mask" "F.Paste")
			(net "P3V3_M2_0")
		)
		(pad "3" smd rect
			(at 3.750056 -8.750046 270)
			(size 0.2794 1.6002)
			(layers "F.Cu" "F.Mask" "F.Paste")
			(net "GND")
		)
		(pad "4" smd rect
			(at -3.800094 -8.50011 270)
			(size 0.2794 1.6002)
			(layers "F.Cu" "F.Mask" "F.Paste")
			(net "P3V3_M2_0")
		)
		(pad "5" smd rect
			(at 3.750056 -8.24992 270)
			(size 0.2794 1.6002)
			(layers "F.Cu" "F.Mask" "F.Paste")
			(net "P3E_PCH_M2_RX_DN<0>")
		)
		(pad "6" smd rect
			(at -3.800094 -7.999984 270)
			(size 0.2794 1.6002)
			(layers "F.Cu" "F.Mask" "F.Paste")
			(net "NC_M2_0_NC1")
		)
		(pad "7" smd rect
			(at 3.750056 -7.750048 270)
			(size 0.2794 1.6002)
			(layers "F.Cu" "F.Mask" "F.Paste")
			(net "P3E_PCH_M2_RX_DP<0>")
		)
		(pad "8" smd rect
			(at -3.800094 -7.500112 270)
			(size 0.2794 1.6002)
			(layers "F.Cu" "F.Mask" "F.Paste")
			(net "NC_M2_0_NC2")
		)
		(pad "9" smd rect
			(at 3.750056 -7.249922 270)
			(size 0.2794 1.6002)
			(layers "F.Cu" "F.Mask" "F.Paste")
			(net "GND")
		)
		(pad "10" smd rect
			(at -3.800094 -6.999986 270)
			(size 0.2794 1.6002)
			(layers "F.Cu" "F.Mask" "F.Paste")
			(net "LED_M2_SSD_0_ACT_N")
		)
		(pad "11" smd rect
			(at 3.750056 -6.75005 270)
			(size 0.2794 1.6002)
			(layers "F.Cu" "F.Mask" "F.Paste")
			(net "P3E_PCH_M2_TX_C_DP<0>")
		)
		(pad "12" smd rect
			(at -3.800094 -6.500114 270)
			(size 0.2794 1.6002)
			(layers "F.Cu" "F.Mask" "F.Paste")
			(net "P3V3_M2_0")
		)
		(pad "13" smd rect
			(at 3.750056 -6.249924 270)
			(size 0.2794 1.6002)
			(layers "F.Cu" "F.Mask" "F.Paste")
			(net "P3E_PCH_M2_TX_C_DN<0>")
		)
		(pad "14" smd rect
			(at -3.800094 -5.999988 270)
			(size 0.2794 1.6002)
			(layers "F.Cu" "F.Mask" "F.Paste")
			(net "P3V3_M2_0")
		)
		(pad "15" smd rect
			(at 3.750056 -5.750052 270)
			(size 0.2794 1.6002)
			(layers "F.Cu" "F.Mask" "F.Paste")
			(net "GND")
		)
		(pad "16" smd rect
			(at -3.800094 -5.500116 270)
			(size 0.2794 1.6002)
			(layers "F.Cu" "F.Mask" "F.Paste")
			(net "P3V3_M2_0")
		)
		(pad "17" smd rect
			(at 3.750056 -5.249926 270)
			(size 0.2794 1.6002)
			(layers "F.Cu" "F.Mask" "F.Paste")
			(net "P3E_PCH_M2_RX_DN<1>")
		)
		(pad "18" smd rect
			(at -3.800094 -4.99999 270)
			(size 0.2794 1.6002)
			(layers "F.Cu" "F.Mask" "F.Paste")
			(net "P3V3_M2_0")
		)
		(pad "19" smd rect
			(at 3.750056 -4.750054 270)
			(size 0.2794 1.6002)
			(layers "F.Cu" "F.Mask" "F.Paste")
			(net "P3E_PCH_M2_RX_DP<1>")
		)
		(pad "20" smd rect
			(at -3.800094 -4.500118 270)
			(size 0.2794 1.6002)
			(layers "F.Cu" "F.Mask" "F.Paste")
			(net "NC_M2_0_NC3")
		)
		(pad "21" smd rect
			(at 3.750056 -4.249928 270)
			(size 0.2794 1.6002)
			(layers "F.Cu" "F.Mask" "F.Paste")
			(net "GND")
		)
		(pad "22" smd rect
			(at -3.800094 -3.999992 270)
			(size 0.2794 1.6002)
			(layers "F.Cu" "F.Mask" "F.Paste")
			(net "NC_M2_0_NC4")
		)
		(pad "23" smd rect
			(at 3.750056 -3.750056 270)
			(size 0.2794 1.6002)
			(layers "F.Cu" "F.Mask" "F.Paste")
			(net "P3E_PCH_M2_TX_C_DP<1>")
		)
		(pad "24" smd rect
			(at -3.800094 -3.50012 270)
			(size 0.2794 1.6002)
			(layers "F.Cu" "F.Mask" "F.Paste")
			(net "NC_M2_0_NC5")
		)
		(pad "25" smd rect
			(at 3.750056 -3.24993 270)
			(size 0.2794 1.6002)
			(layers "F.Cu" "F.Mask" "F.Paste")
			(net "P3E_PCH_M2_TX_C_DN<1>")
		)
		(pad "26" smd rect
			(at -3.800094 -2.999994 270)
			(size 0.2794 1.6002)
			(layers "F.Cu" "F.Mask" "F.Paste")
			(net "NC_M2_0_NC6")
		)
		(pad "27" smd rect
			(at 3.750056 -2.750058 270)
			(size 0.2794 1.6002)
			(layers "F.Cu" "F.Mask" "F.Paste")
			(net "GND")
		)
		(pad "28" smd rect
			(at -3.800094 -2.500122 270)
			(size 0.2794 1.6002)
			(layers "F.Cu" "F.Mask" "F.Paste")
			(net "NC_M2_0_NC7")
		)
		(pad "29" smd rect
			(at 3.750056 -2.249932 270)
			(size 0.2794 1.6002)
			(layers "F.Cu" "F.Mask" "F.Paste")
			(net "P3E_PCH_M2_RX_DN<2>")
		)
		(pad "30" smd rect
			(at -3.800094 -1.999996 270)
			(size 0.2794 1.6002)
			(layers "F.Cu" "F.Mask" "F.Paste")
			(net "NC_M2_0_NC8")
		)
		(pad "31" smd rect
			(at 3.750056 -1.75006 270)
			(size 0.2794 1.6002)
			(layers "F.Cu" "F.Mask" "F.Paste")
			(net "P3E_PCH_M2_RX_DP<2>")
		)
		(pad "32" smd rect
			(at -3.800094 -1.500124 270)
			(size 0.2794 1.6002)
			(layers "F.Cu" "F.Mask" "F.Paste")
			(net "NC_M2_0_NC9")
		)
		(pad "33" smd rect
			(at 3.750056 -1.249934 270)
			(size 0.2794 1.6002)
			(layers "F.Cu" "F.Mask" "F.Paste")
			(net "GND")
		)
		(pad "34" smd rect
			(at -3.800094 -0.999998 270)
			(size 0.2794 1.6002)
			(layers "F.Cu" "F.Mask" "F.Paste")
			(net "NC_M2_0_NC10")
		)
		(pad "35" smd rect
			(at 3.750056 -0.750062 270)
			(size 0.2794 1.6002)
			(layers "F.Cu" "F.Mask" "F.Paste")
			(net "P3E_PCH_M2_TX_C_DP<2>")
		)
		(pad "36" smd rect
			(at -3.800094 -0.499872 270)
			(size 0.2794 1.6002)
			(layers "F.Cu" "F.Mask" "F.Paste")
			(net "NC_M2_0_NC11")
		)
		(pad "37" smd rect
			(at 3.750056 -0.249936 270)
			(size 0.2794 1.6002)
			(layers "F.Cu" "F.Mask" "F.Paste")
			(net "P3E_PCH_M2_TX_C_DN<2>")
		)
		(pad "38" smd rect
			(at -3.800094 0 270)
			(size 0.2794 1.6002)
			(layers "F.Cu" "F.Mask" "F.Paste")
			(net "PD_M2_0_DEVSLP")
		)
		(pad "39" smd rect
			(at 3.750056 0.249936 270)
			(size 0.2794 1.6002)
			(layers "F.Cu" "F.Mask" "F.Paste")
			(net "GND")
		)
		(pad "40" smd rect
			(at -3.800094 0.499872 270)
			(size 0.2794 1.6002)
			(layers "F.Cu" "F.Mask" "F.Paste")
			(net "SMB_M2_P0_1V8AUX_SCL")
		)
		(pad "41" smd rect
			(at 3.750056 0.750062 270)
			(size 0.2794 1.6002)
			(layers "F.Cu" "F.Mask" "F.Paste")
			(net "P3E_PCH_M2_RX_DN<3>")
		)
		(pad "42" smd rect
			(at -3.800094 0.999998 270)
			(size 0.2794 1.6002)
			(layers "F.Cu" "F.Mask" "F.Paste")
			(net "SMB_M2_P0_1V8AUX_SDA")
		)
		(pad "43" smd rect
			(at 3.750056 1.249934 270)
			(size 0.2794 1.6002)
			(layers "F.Cu" "F.Mask" "F.Paste")
			(net "P3E_PCH_M2_RX_DP<3>")
		)
		(pad "44" smd rect
			(at -3.800094 1.500124 270)
			(size 0.2794 1.6002)
			(layers "F.Cu" "F.Mask" "F.Paste")
			(net "NC_M2_0_NC14")
		)
		(pad "45" smd rect
			(at 3.750056 1.75006 270)
			(size 0.2794 1.6002)
			(layers "F.Cu" "F.Mask" "F.Paste")
			(net "GND")
		)
		(pad "46" smd rect
			(at -3.800094 1.999996 270)
			(size 0.2794 1.6002)
			(layers "F.Cu" "F.Mask" "F.Paste")
			(net "NC_M2_0_NC15")
		)
		(pad "47" smd rect
			(at 3.750056 2.249932 270)
			(size 0.2794 1.6002)
			(layers "F.Cu" "F.Mask" "F.Paste")
			(net "P3E_PCH_M2_TX_C_DP<3>")
		)
		(pad "48" smd rect
			(at -3.800094 2.500122 270)
			(size 0.2794 1.6002)
			(layers "F.Cu" "F.Mask" "F.Paste")
			(net "NC_M2_0_NC16")
		)
		(pad "49" smd rect
			(at 3.750056 2.750058 270)
			(size 0.2794 1.6002)
			(layers "F.Cu" "F.Mask" "F.Paste")
			(net "P3E_PCH_M2_TX_C_DN<3>")
		)
		(pad "50" smd rect
			(at -3.800094 2.999994 270)
			(size 0.2794 1.6002)
			(layers "F.Cu" "F.Mask" "F.Paste")
			(net "RST_PCIE_PCH_DEV_0_N")
		)
		(pad "51" smd rect
			(at 3.750056 3.24993 270)
			(size 0.2794 1.6002)
			(layers "F.Cu" "F.Mask" "F.Paste")
			(net "GND")
		)
		(pad "52" smd rect
			(at -3.800094 3.50012 270)
			(size 0.2794 1.6002)
			(layers "F.Cu" "F.Mask" "F.Paste")
			(net "M2_SSD0_CLKREQ_EN_N_BUF")
		)
		(pad "53" smd rect
			(at 3.750056 3.750056 270)
			(size 0.2794 1.6002)
			(layers "F.Cu" "F.Mask" "F.Paste")
			(net "CLK_100M_PE_M2_0_DN")
		)
		(pad "54" smd rect
			(at -3.800094 3.999992 270)
			(size 0.2794 1.6002)
			(layers "F.Cu" "F.Mask" "F.Paste")
			(net "M2_0_PEWAKE_N")
		)
		(pad "55" smd rect
			(at 3.750056 4.249928 270)
			(size 0.2794 1.6002)
			(layers "F.Cu" "F.Mask" "F.Paste")
			(net "CLK_100M_PE_M2_0_DP")
		)
		(pad "56" smd rect
			(at -3.800094 4.500118 270)
			(size 0.2794 1.6002)
			(layers "F.Cu" "F.Mask" "F.Paste")
			(net "NC_M2_0_NC17")
		)
		(pad "57" smd rect
			(at 3.750056 4.750054 270)
			(size 0.2794 1.6002)
			(layers "F.Cu" "F.Mask" "F.Paste")
			(net "GND")
		)
		(pad "58" smd rect
			(at -3.800094 4.99999 270)
			(size 0.2794 1.6002)
			(layers "F.Cu" "F.Mask" "F.Paste")
			(net "NC_M2_0_NC18")
		)
		(pad "67" smd rect
			(at 3.750056 7.249922 270)
			(size 0.2794 1.6002)
			(layers "F.Cu" "F.Mask" "F.Paste")
			(net "NC_M2_0_NC19")
		)
		(pad "68" smd rect
			(at -3.800094 7.500112 270)
			(size 0.2794 1.6002)
			(layers "F.Cu" "F.Mask" "F.Paste")
			(net "NC_M2_0_SUSCLK")
		)
		(pad "69" smd rect
			(at 3.750056 7.750048 270)
			(size 0.2794 1.6002)
			(layers "F.Cu" "F.Mask" "F.Paste")
			(net "FM_M2_SSD_0_PEDET")
		)
		(pad "70" smd rect
			(at -3.800094 7.999984 270)
			(size 0.2794 1.6002)
			(layers "F.Cu" "F.Mask" "F.Paste")
			(net "P3V3_M2_0")
		)
		(pad "71" smd rect
			(at 3.750056 8.24992 270)
			(size 0.2794 1.6002)
			(layers "F.Cu" "F.Mask" "F.Paste")
			(net "GND")
		)
		(pad "72" smd rect
			(at -3.800094 8.50011 270)
			(size 0.2794 1.6002)
			(layers "F.Cu" "F.Mask" "F.Paste")
			(net "P3V3_M2_0")
		)
		(pad "73" smd rect
			(at 3.750056 8.750046 270)
			(size 0.2794 1.6002)
			(layers "F.Cu" "F.Mask" "F.Paste")
			(net "GND")
		)
		(pad "74" smd rect
			(at -3.800094 8.999982 270)
			(size 0.2794 1.6002)
			(layers "F.Cu" "F.Mask" "F.Paste")
			(net "P3V3_M2_0")
		)
		(pad "75" smd rect
			(at 3.750056 9.249918 270)
			(size 0.2794 1.6002)
			(layers "F.Cu" "F.Mask" "F.Paste")
			(net "GND")
		)
		(pad "G1" smd rect
			(at 2.975102 -10.349992 270)
			(size 1.2446 2.794)
			(layers "F.Cu" "F.Mask" "F.Paste")
			(net "GND")
		)
		(pad "G2" smd rect
			(at 2.975102 10.349992 270)
			(size 1.2446 2.794)
			(layers "F.Cu" "F.Mask" "F.Paste")
			(net "GND")
		)
	)
)
